# S9S_MB_2U (Grand Teton) — schematic netlist excerpt (pin names and nets, part order shuffled) for the footprints in the layout excerpt that follows; sources: Cadence DE-HDL packaged netlist, KiCad conversion of 03242023_DA0F0TMBIJ0_F0T_Motherboard_J_brd_V01_OCP.brd

J5  SCONN288_ADR50017P130CC  SCONN288_ADR50017-P130CC IO  pkg DDR288S_1-1VXB  page 86
  VIN_BULK0  = P12V_S3_AUX_CPU0_NVDIMM
  RFU0  = TP_CHC_CPU0_DIMM1_FRU_0
  VIN_MGMT  = P3V3_AUX
  HSCL  = I3C_SPD_DDRABCD_CPU0_LVC1_SCL_4
  HSDA  = I3C_SPD_DDRABCD_CPU0_LVC1_SDA
  VSS0  = GND
  DQ0_A  = M_C_CPU0_SA_DQ<0>
  VSS1  = GND
  DQ1_A  = M_C_CPU0_SA_DQ<1>
  VSS2  = GND
  DQS0_A_T  = M_C_CPU0_SA_DQS_DP<0>
  DQS0_A_C  = M_C_CPU0_SA_DQS_DN<0>
  VSS3  = GND
  DQ4_A  = M_C_CPU0_SA_DQ<4>
  VSS4  = GND
  DQ5_A  = M_C_CPU0_SA_DQ<5>
  VSS5  = GND
  DQ8_A  = M_C_CPU0_SA_DQ<8>
  VSS6  = GND
  DQ9_A  = M_C_CPU0_SA_DQ<9>
  VSS7  = GND
  DQS1_A_T  = M_C_CPU0_SA_DQS_DP<1>
  DQS1_A_C  = M_C_CPU0_SA_DQS_DN<1>
  VSS8  = GND
  DQ12_A  = M_C_CPU0_SA_DQ<12>
  VSS9  = GND
  DQ13_A  = M_C_CPU0_SA_DQ<13>
  VSS10  = GND
  DQ16_A  = M_C_CPU0_SA_DQ<16>
  VSS11  = GND
  DQ17_A  = M_C_CPU0_SA_DQ<17>
  VSS12  = GND
  DQS2_A_T  = M_C_CPU0_SA_DQS_DP<2>
  DQS2_A_C  = M_C_CPU0_SA_DQS_DN<2>
  VSS13  = GND
  DQ20_A  = M_C_CPU0_SA_DQ<20>
  VSS14  = GND
  DQ21_A  = M_C_CPU0_SA_DQ<21>
  VSS15  = GND
  DQ24_A  = M_C_CPU0_SA_DQ<24>
  VSS16  = GND
  DQ25_A  = M_C_CPU0_SA_DQ<25>
  VSS17  = GND
  DQS3_A_T  = M_C_CPU0_SA_DQS_DP<3>
  DQS3_A_C  = M_C_CPU0_SA_DQS_DN<3>
  VSS18  = GND
  DQ28_A  = M_C_CPU0_SA_DQ<28>
  VSS19  = GND
  DQ29_A  = M_C_CPU0_SA_DQ<29>
  VSS20  = GND
  CB0_A  = M_C_CPU0_SA_CB<0>
  VSS21  = GND
  CB1_A  = M_C_CPU0_SA_CB<1>
  VSS22  = GND
  DQS4_A_T  = M_C_CPU0_SA_DQS_DP<4>
  DQS4_A_C  = M_C_CPU0_SA_DQS_DN<4>
  VSS23  = GND
  CB4_A  = M_C_CPU0_SA_CB<4>
  VSS24  = GND
  CB5_A  = M_C_CPU0_SA_CB<5>
  VSS25  = GND
  ALERT_N  = M_C_CPU0_ALERT_N
  VSS26  = GND
  CS0_A_N  = M_C_CPU0_SA_CS_N<0>
  VSS27  = GND
  CA0_A  = M_C_CPU0_SA_CA<0>
  VSS28  = GND
  CA2_A  = M_C_CPU0_SA_CA<2>
  VSS29  = GND
  CA4_A  = M_C_CPU0_SA_CA<4>
  VSS30  = GND
  CA6_A  = M_C_CPU0_SA_CA<6>
  VSS31  = GND
  PAR_A  = M_C_CPU0_SA_PAR
  VSS32  = GND
  CA0_B  = M_C_CPU0_SB_CA<0>
  VSS33  = GND
  CA2_B  = M_C_CPU0_SB_CA<2>
  VSS34  = GND
  CA4_B  = M_C_CPU0_SB_CA<4>
  VSS35  = GND
  CA6_B  = M_C_CPU0_SB_CA<6>
  VSS36  = GND
  CS0_B_N  = M_C_CPU0_SB_CS_N<0>
  VSS37  = GND
  \lbd||rsp_a_n\  = M_C_CPU0_SA_RSP<0>
  \lbs||rsp_b_n\  = M_C_CPU0_SB_RSP<0>
  VSS38  = GND
  CB4_B  = M_C_CPU0_SB_CB<4>
  VSS39  = GND
  CB5_B  = M_C_CPU0_SB_CB<5>
  VSS40  = GND
  \dqs9_b_t||tdqs9_b_t||dbi4_b_n\  = M_C_CPU0_SB_DQS_DP<9>
  \dqs9_b_c||tdqs9_b_c\  = M_C_CPU0_SB_DQS_DN<9>
  VSS41  = GND
  CB0_B  = M_C_CPU0_SB_CB<0>
  VSS42  = GND
  CB1_B  = M_C_CPU0_SB_CB<1>
  VSS43  = GND
  DQ0_B  = M_C_CPU0_SB_DQ<0>
  VSS44  = GND
  DQ1_B  = M_C_CPU0_SB_DQ<1>
  VSS45  = GND
  DQS0_B_T  = M_C_CPU0_SB_DQS_DP<0>
  DQS0_B_C  = M_C_CPU0_SB_DQS_DN<0>
  VSS46  = GND
  DQ4_B  = M_C_CPU0_SB_DQ<4>
  VSS47  = GND
  DQ5_B  = M_C_CPU0_SB_DQ<5>
  VSS48  = GND
  DQ8_B  = M_C_CPU0_SB_DQ<8>
  VSS49  = GND
  DQ9_B  = M_C_CPU0_SB_DQ<9>
  VSS50  = GND
  DQS1_B_T  = M_C_CPU0_SB_DQS_DP<1>
  DQS1_B_C  = M_C_CPU0_SB_DQS_DN<1>
  VSS51  = GND
  DQ12_B  = M_C_CPU0_SB_DQ<12>
  VSS52  = GND
  DQ13_B  = M_C_CPU0_SB_DQ<13>
  VSS53  = GND
  DQ16_B  = M_C_CPU0_SB_DQ<16>
  VSS54  = GND
  DQ17_B  = M_C_CPU0_SB_DQ<17>
  VSS55  = GND
  DQS2_B_T  = M_C_CPU0_SB_DQS_DP<2>
  DQS2_B_C  = M_C_CPU0_SB_DQS_DN<2>
  VSS56  = GND
  DQ20_B  = M_C_CPU0_SB_DQ<20>
  VSS57  = GND
  DQ21_B  = M_C_CPU0_SB_DQ<21>
  VSS58  = GND
  DQ24_B  = M_C_CPU0_SB_DQ<24>
  VSS59  = GND
  DQ25_B  = M_C_CPU0_SB_DQ<25>
  VSS60  = GND
  DQS3_B_T  = M_C_CPU0_SB_DQS_DP<3>
  DQS3_B_C  = M_C_CPU0_SB_DQS_DN<3>
  VSS61  = GND
  DQ28_B  = M_C_CPU0_SB_DQ<28>
  VSS62  = GND
  DQ29_B  = M_C_CPU0_SB_DQ<29>
  VSS63  = GND
  RFU1  = TP_CHC_CPU0_DIMM1_FRU_1
  VIN_BULK1  = P12V_S3_AUX_CPU0_NVDIMM
  VIN_BULK2  = P12V_S3_AUX_CPU0_NVDIMM
  \pwr_good||fail_n\  = PWRGD_CHC_CPU0_DIMM1
  HSA  = PD_CHC_CPU0_DIMM1_SAA
  RFU2  = TP_CHC_CPU0_DIMM1_FRU_2
  RFU3  = TP_CHC_CPU0_DIMM1_FRU_3
  VSS64  = GND
  DQ2_A  = M_C_CPU0_SA_DQ<2>
  VSS65  = GND
  DQ3_A  = M_C_CPU0_SA_DQ<3>
  VSS66  = GND
  \dqs5_a_c||tdqs5_a_c||dqs5_a_t||tdqs5_a_t\  = M_C_CPU0_SA_DQS_DN<5>
  \dqs5_a_t||tdqs5_a_t\  = M_C_CPU0_SA_DQS_DP<5>
  VSS67  = GND
  DQ6_A  = M_C_CPU0_SA_DQ<6>
  VSS68  = GND
  DQ7_A  = M_C_CPU0_SA_DQ<7>
  VSS69  = GND
  DQ10_A  = M_C_CPU0_SA_DQ<10>
  VSS70  = GND
  DQ11_A  = M_C_CPU0_SA_DQ<11>
  VSS71  = GND
  \dqs6_a_c||tdqs6_a_c||dqs6_a_t||tdqs6_a_t\  = M_C_CPU0_SA_DQS_DN<6>
  \dqs6_a_t||tdqs6_a_t\  = M_C_CPU0_SA_DQS_DP<6>
  VSS72  = GND
  DQ14_A  = M_C_CPU0_SA_DQ<14>
  VSS73  = GND
  DQ15_A  = M_C_CPU0_SA_DQ<15>
  VSS74  = GND
  DQ18_A  = M_C_CPU0_SA_DQ<18>
  VSS75  = GND
  DQ19_A  = M_C_CPU0_SA_DQ<19>
  VSS76  = GND
  \dqs7_a_c||tdqs7_a_c\  = M_C_CPU0_SA_DQS_DN<7>
  \dqs7_a_t||tdqs7_a_t\  = M_C_CPU0_SA_DQS_DP<7>
  VSS77  = GND
  DQ22_A  = M_C_CPU0_SA_DQ<22>
  VSS78  = GND
  DQ23_A  = M_C_CPU0_SA_DQ<23>
  VSS79  = GND
  DQ26_A  = M_C_CPU0_SA_DQ<26>
  VSS80  = GND
  DQ27_A  = M_C_CPU0_SA_DQ<27>
  VSS81  = GND
  \dqs8_a_c||tdqs8_a_c\  = M_C_CPU0_SA_DQS_DN<8>
  \dqs8_a_t||tdqs8_a_t\  = M_C_CPU0_SA_DQS_DP<8>
  VSS82  = GND
  DQ30_A  = M_C_CPU0_SA_DQ<30>
  VSS83  = GND
  DQ31_A  = M_C_CPU0_SA_DQ<31>
  VSS84  = GND
  CB2_A  = M_C_CPU0_SA_CB<2>
  VSS85  = GND
  CB3_A  = M_C_CPU0_SA_CB<3>
  VSS86  = GND
  \dqs9_a_c||tdqs9_a_c\  = M_C_CPU0_SA_DQS_DN<9>
  \dqs9_a_t||tdqs9_a_t\  = M_C_CPU0_SA_DQS_DP<9>
  VSS87  = GND
  CB6_A  = M_C_CPU0_SA_CB<6>
  VSS88  = GND
  CB7_A  = M_C_CPU0_SA_CB<7>
  VSS89  = GND
  RESET_N  = RST_M_CD_CPU0_FPGA_N
  VSS90  = GND
  CS1_A_N  = M_C_CPU0_SA_CS_N<1>
  VSS91  = GND
  CA1_A  = M_C_CPU0_SA_CA<1>
  VSS92  = GND
  CA3_A  = M_C_CPU0_SA_CA<3>
  VSS93  = GND
  CA5_A  = M_C_CPU0_SA_CA<5>
  VSS94  = GND
  CK_T  = M_C_CPU0_CLK_DP<0>
  CK_C  = M_C_CPU0_CLK_DN<0>
  VSS95  = GND
  RFU4  = TP_CHC_CPU0_DIMM1_FRU_4
  CA1_B  = M_C_CPU0_SB_CA<1>
  VSS96  = GND
  CA3_B  = M_C_CPU0_SB_CA<3>
  VSS97  = GND
  CA5_B  = M_C_CPU0_SB_CA<5>
  VSS98  = GND
  PAR_B  = M_C_CPU0_SB_PAR
  VSS99  = GND
  CS1_B_N  = M_C_CPU0_SB_CS_N<1>
  VSS100  = GND
  RFU5  = TP_CHC_CPU0_DIMM1_FRU_5
  RFU6  = TP_CHC_CPU0_DIMM1_FRU_6
  VSS101  = GND
  CB6_B  = M_C_CPU0_SB_CB<6>
  VSS102  = GND
  CB7_B  = M_C_CPU0_SB_CB<7>
  VSS103  = GND
  DQS4_B_C  = M_C_CPU0_SB_DQS_DN<4>
  DQS4_B_T  = M_C_CPU0_SB_DQS_DP<4>
  VSS104  = GND
  CB2_B  = M_C_CPU0_SB_CB<2>
  VSS105  = GND
  CB3_B  = M_C_CPU0_SB_CB<3>
  VSS106  = GND
  DQ2_B  = M_C_CPU0_SB_DQ<2>
  VSS107  = GND
  DQ3_B  = M_C_CPU0_SB_DQ<3>
  VSS108  = GND
  \dqs5_b_c||tdqs5_b_c\  = M_C_CPU0_SB_DQS_DN<5>
  \dqs5_b_t||tdqs5_b_t\  = M_C_CPU0_SB_DQS_DP<5>
  VSS109  = GND
  DQ6_B  = M_C_CPU0_SB_DQ<6>
  VSS110  = GND
  DQ7_B  = M_C_CPU0_SB_DQ<7>
  VSS111  = GND
  DQ10_B  = M_C_CPU0_SB_DQ<10>
  VSS112  = GND
  DQ11_B  = M_C_CPU0_SB_DQ<11>
  VSS113  = GND
  \dqs6_b_c||tdqs6_b_c\  = M_C_CPU0_SB_DQS_DN<6>
  \dqs6_b_t||tdqs6_b_t\  = M_C_CPU0_SB_DQS_DP<6>
  VSS114  = GND
  DQ14_B  = M_C_CPU0_SB_DQ<14>
  VSS115  = GND
  DQ15_B  = M_C_CPU0_SB_DQ<15>
  VSS116  = GND
  DQ18_B  = M_C_CPU0_SB_DQ<18>
  VSS117  = GND
  DQ19_B  = M_C_CPU0_SB_DQ<19>
  VSS118  = GND
  \dqs7_b_c||tdqs7_b_c\  = M_C_CPU0_SB_DQS_DN<7>
  \dqs7_b_t||tdqs7_b_t\  = M_C_CPU0_SB_DQS_DP<7>
  VSS119  = GND
  DQ22_B  = M_C_CPU0_SB_DQ<22>
  VSS120  = GND
  DQ23_B  = M_C_CPU0_SB_DQ<23>
  VSS121  = GND
  DQ26_B  = M_C_CPU0_SB_DQ<26>
  VSS122  = GND
  DQ27_B  = M_C_CPU0_SB_DQ<27>
  VSS123  = GND
  \dqs8_b_c||tdqs8_b_c\  = M_C_CPU0_SB_DQS_DN<8>
  \dqs8_b_t||tdqs8_b_t\  = M_C_CPU0_SB_DQS_DP<8>
  VSS124  = GND
  DQ30_B  = M_C_CPU0_SB_DQ<30>
  VSS125  = GND
  DQ31_B  = M_C_CPU0_SB_DQ<31>
  VSS126  = GND
  G1  = GND
  G2  = GND
  G3  = GND

(kicad_pcb
	(version 20260206)
	(generator "pcbnew")
	(generator_version "10.0")
	(general
		(thickness 1.6)
		(legacy_teardrops no)
	)
	(paper "A4")
	(title_block
		(title "03242023_DA0F0TMBIJ0_F0T_Motherboard_J_brd_V01_OCP.brd")
		(comment 1 "Grand Teton / footprint 885 of 6105 (J5), pads 229-274 of 291")
	)
	(layers
		(0 "F.Cu" signal "TOP")
		(4 "In1.Cu" signal "GND")
		(6 "In2.Cu" signal "IN1")
		(8 "In3.Cu" signal "GND1")
		(10 "In4.Cu" signal "IN2")
		(12 "In5.Cu" signal "GND2")
		(14 "In6.Cu" signal "IN3")
		(16 "In7.Cu" signal "GND3")
		(18 "In8.Cu" signal "VCC")
		(20 "In9.Cu" signal "VCC1")
		(22 "In10.Cu" signal "GND4")
		(24 "In11.Cu" signal "IN4")
		(26 "In12.Cu" signal "GND5")
		(28 "In13.Cu" signal "IN5")
		(30 "In14.Cu" signal "GND6")
		(32 "In15.Cu" signal "IN6")
		(34 "In16.Cu" signal "GND7")
		(2 "B.Cu" signal "BOTTOM")
		(9 "F.Adhes" user "F.Adhesive")
		(11 "B.Adhes" user "B.Adhesive")
		(13 "F.Paste" user "Package Geometry/Pastemask Top")
		(15 "B.Paste" user "Package Geometry/Pastemask Bottom")
		(5 "F.SilkS" user "Ref Des/Silkscreen Top")
		(7 "B.SilkS" user "Ref Des/Silkscreen Bottom")
		(1 "F.Mask" user "Board Geometry/Soldermask Top")
		(3 "B.Mask" user "Board Geometry/Soldermask Bottom")
		(17 "Dwgs.User" user "User.Drawings")
		(19 "Cmts.User" user "User.Comments")
		(21 "Eco1.User" user "User.Eco1")
		(23 "Eco2.User" user "User.Eco2")
		(25 "Edge.Cuts" user "Board Geometry/Outline")
		(27 "Margin" user)
		(31 "F.CrtYd" user "Package Geometry/Place Bound Top")
		(29 "B.CrtYd" user "Package Geometry/Place Bound Bottom")
		(35 "F.Fab" user "Ref Des/Assembly Top")
		(33 "B.Fab" user "Ref Des/Assembly Bottom")
	)
	(footprint ""
		(layer "F.Cu")
		(at 273.218148 -258.091686)
		(property "Reference" "J5"
			(at -3.683 -81.702148 0)
			(unlocked yes)
			(layer "F.SilkS")
			(effects
				(font
					(size 0.7874 0.5842)
					(thickness 0.1524)
				)
				(justify left)
			)
		)
		(property "Value" ""
			(at 0 0 0)
			(layer "F.Fab")
			(effects
				(font
					(size 1.27 1.27)
				)
			)
		)
		(duplicate_pad_numbers_are_jumpers no)
		(pad "229" smd rect
			(at 2.050034 13.17498 270)
			(size 0.519938 1.4986)
			(layers "F.Cu" "F.Mask" "F.Paste")
			(net "M_C_CPU0_SB_CS_N<1>")
		)
		(pad "230" smd rect
			(at 2.050034 14.025118 270)
			(size 0.519938 1.4986)
			(layers "F.Cu" "F.Mask" "F.Paste")
			(net "GND")
		)
		(pad "231" smd rect
			(at 2.050034 14.875002 270)
			(size 0.519938 1.4986)
			(layers "F.Cu" "F.Mask" "F.Paste")
			(net "TP_CHC_CPU0_DIMM1_FRU_5")
		)
		(pad "232" smd rect
			(at 2.050034 15.724886 270)
			(size 0.519938 1.4986)
			(layers "F.Cu" "F.Mask" "F.Paste")
			(net "TP_CHC_CPU0_DIMM1_FRU_6")
		)
		(pad "233" smd rect
			(at 2.050034 16.575024 270)
			(size 0.519938 1.4986)
			(layers "F.Cu" "F.Mask" "F.Paste")
			(net "GND")
		)
		(pad "234" smd rect
			(at 2.050034 17.424908 270)
			(size 0.519938 1.4986)
			(layers "F.Cu" "F.Mask" "F.Paste")
			(net "M_C_CPU0_SB_CB<6>")
		)
		(pad "235" smd rect
			(at 2.050034 18.275046 270)
			(size 0.519938 1.4986)
			(layers "F.Cu" "F.Mask" "F.Paste")
			(net "GND")
		)
		(pad "236" smd rect
			(at 2.050034 19.12493 270)
			(size 0.519938 1.4986)
			(layers "F.Cu" "F.Mask" "F.Paste")
			(net "M_C_CPU0_SB_CB<7>")
		)
		(pad "237" smd rect
			(at 2.050034 19.975068 270)
			(size 0.519938 1.4986)
			(layers "F.Cu" "F.Mask" "F.Paste")
			(net "GND")
		)
		(pad "238" smd rect
			(at 2.050034 20.824952 270)
			(size 0.519938 1.4986)
			(layers "F.Cu" "F.Mask" "F.Paste")
			(net "M_C_CPU0_SB_DQS_DN<4>")
		)
		(pad "239" smd rect
			(at 2.050034 21.67509 270)
			(size 0.519938 1.4986)
			(layers "F.Cu" "F.Mask" "F.Paste")
			(net "M_C_CPU0_SB_DQS_DP<4>")
		)
		(pad "240" smd rect
			(at 2.050034 22.524974 270)
			(size 0.519938 1.4986)
			(layers "F.Cu" "F.Mask" "F.Paste")
			(net "GND")
		)
		(pad "241" smd rect
			(at 2.050034 23.375112 270)
			(size 0.519938 1.4986)
			(layers "F.Cu" "F.Mask" "F.Paste")
			(net "M_C_CPU0_SB_CB<2>")
		)
		(pad "242" smd rect
			(at 2.050034 24.224996 270)
			(size 0.519938 1.4986)
			(layers "F.Cu" "F.Mask" "F.Paste")
			(net "GND")
		)
		(pad "243" smd rect
			(at 2.050034 25.07488 270)
			(size 0.519938 1.4986)
			(layers "F.Cu" "F.Mask" "F.Paste")
			(net "M_C_CPU0_SB_CB<3>")
		)
		(pad "244" smd rect
			(at 2.050034 25.925018 270)
			(size 0.519938 1.4986)
			(layers "F.Cu" "F.Mask" "F.Paste")
			(net "GND")
		)
		(pad "245" smd rect
			(at 2.050034 26.774902 270)
			(size 0.519938 1.4986)
			(layers "F.Cu" "F.Mask" "F.Paste")
			(net "M_C_CPU0_SB_DQ<2>")
		)
		(pad "246" smd rect
			(at 2.050034 27.62504 270)
			(size 0.519938 1.4986)
			(layers "F.Cu" "F.Mask" "F.Paste")
			(net "GND")
		)
		(pad "247" smd rect
			(at 2.050034 28.474924 270)
			(size 0.519938 1.4986)
			(layers "F.Cu" "F.Mask" "F.Paste")
			(net "M_C_CPU0_SB_DQ<3>")
		)
		(pad "248" smd rect
			(at 2.050034 29.325062 270)
			(size 0.519938 1.4986)
			(layers "F.Cu" "F.Mask" "F.Paste")
			(net "GND")
		)
		(pad "249" smd rect
			(at 2.050034 30.174946 270)
			(size 0.519938 1.4986)
			(layers "F.Cu" "F.Mask" "F.Paste")
			(net "M_C_CPU0_SB_DQS_DN<5>")
		)
		(pad "250" smd rect
			(at 2.050034 31.025084 270)
			(size 0.519938 1.4986)
			(layers "F.Cu" "F.Mask" "F.Paste")
			(net "M_C_CPU0_SB_DQS_DP<5>")
		)
		(pad "251" smd rect
			(at 2.050034 31.874968 270)
			(size 0.519938 1.4986)
			(layers "F.Cu" "F.Mask" "F.Paste")
			(net "GND")
		)
		(pad "252" smd rect
			(at 2.050034 32.725106 270)
			(size 0.519938 1.4986)
			(layers "F.Cu" "F.Mask" "F.Paste")
			(net "M_C_CPU0_SB_DQ<6>")
		)
		(pad "253" smd rect
			(at 2.050034 33.57499 270)
			(size 0.519938 1.4986)
			(layers "F.Cu" "F.Mask" "F.Paste")
			(net "GND")
		)
		(pad "254" smd rect
			(at 2.050034 34.425128 270)
			(size 0.519938 1.4986)
			(layers "F.Cu" "F.Mask" "F.Paste")
			(net "M_C_CPU0_SB_DQ<7>")
		)
		(pad "255" smd rect
			(at 2.050034 35.275012 270)
			(size 0.519938 1.4986)
			(layers "F.Cu" "F.Mask" "F.Paste")
			(net "GND")
		)
		(pad "256" smd rect
			(at 2.050034 36.124896 270)
			(size 0.519938 1.4986)
			(layers "F.Cu" "F.Mask" "F.Paste")
			(net "M_C_CPU0_SB_DQ<10>")
		)
		(pad "257" smd rect
			(at 2.050034 36.975034 270)
			(size 0.519938 1.4986)
			(layers "F.Cu" "F.Mask" "F.Paste")
			(net "GND")
		)
		(pad "258" smd rect
			(at 2.050034 37.824918 270)
			(size 0.519938 1.4986)
			(layers "F.Cu" "F.Mask" "F.Paste")
			(net "M_C_CPU0_SB_DQ<11>")
		)
		(pad "259" smd rect
			(at 2.050034 38.675056 270)
			(size 0.519938 1.4986)
			(layers "F.Cu" "F.Mask" "F.Paste")
			(net "GND")
		)
		(pad "260" smd rect
			(at 2.050034 39.52494 270)
			(size 0.519938 1.4986)
			(layers "F.Cu" "F.Mask" "F.Paste")
			(net "M_C_CPU0_SB_DQS_DN<6>")
		)
		(pad "261" smd rect
			(at 2.050034 40.375078 270)
			(size 0.519938 1.4986)
			(layers "F.Cu" "F.Mask" "F.Paste")
			(net "M_C_CPU0_SB_DQS_DP<6>")
		)
		(pad "262" smd rect
			(at 2.050034 41.224962 270)
			(size 0.519938 1.4986)
			(layers "F.Cu" "F.Mask" "F.Paste")
			(net "GND")
		)
		(pad "263" smd rect
			(at 2.050034 42.0751 270)
			(size 0.519938 1.4986)
			(layers "F.Cu" "F.Mask" "F.Paste")
			(net "M_C_CPU0_SB_DQ<14>")
		)
		(pad "264" smd rect
			(at 2.050034 42.924984 270)
			(size 0.519938 1.4986)
			(layers "F.Cu" "F.Mask" "F.Paste")
			(net "GND")
		)
		(pad "265" smd rect
			(at 2.050034 43.775122 270)
			(size 0.519938 1.4986)
			(layers "F.Cu" "F.Mask" "F.Paste")
			(net "M_C_CPU0_SB_DQ<15>")
		)
		(pad "266" smd rect
			(at 2.050034 44.625006 270)
			(size 0.519938 1.4986)
			(layers "F.Cu" "F.Mask" "F.Paste")
			(net "GND")
		)
		(pad "267" smd rect
			(at 2.050034 45.47489 270)
			(size 0.519938 1.4986)
			(layers "F.Cu" "F.Mask" "F.Paste")
			(net "M_C_CPU0_SB_DQ<18>")
		)
		(pad "268" smd rect
			(at 2.050034 46.325028 270)
			(size 0.519938 1.4986)
			(layers "F.Cu" "F.Mask" "F.Paste")
			(net "GND")
		)
		(pad "269" smd rect
			(at 2.050034 47.174912 270)
			(size 0.519938 1.4986)
			(layers "F.Cu" "F.Mask" "F.Paste")
			(net "M_C_CPU0_SB_DQ<19>")
		)
		(pad "270" smd rect
			(at 2.050034 48.02505 270)
			(size 0.519938 1.4986)
			(layers "F.Cu" "F.Mask" "F.Paste")
			(net "GND")
		)
		(pad "271" smd rect
			(at 2.050034 48.874934 270)
			(size 0.519938 1.4986)
			(layers "F.Cu" "F.Mask" "F.Paste")
			(net "M_C_CPU0_SB_DQS_DN<7>")
		)
		(pad "272" smd rect
			(at 2.050034 49.725072 270)
			(size 0.519938 1.4986)
			(layers "F.Cu" "F.Mask" "F.Paste")
			(net "M_C_CPU0_SB_DQS_DP<7>")
		)
		(pad "273" smd rect
			(at 2.050034 50.574956 270)
			(size 0.519938 1.4986)
			(layers "F.Cu" "F.Mask" "F.Paste")
			(net "GND")
		)
		(pad "274" smd rect
			(at 2.050034 51.425094 270)
			(size 0.519938 1.4986)
			(layers "F.Cu" "F.Mask" "F.Paste")
			(net "M_C_CPU0_SB_DQ<22>")
		)
	)
)
